# S9S_MB_2U (Grand Teton) — schematic netlist excerpt (pin names and nets, part order shuffled) for the footprints in the layout excerpt that follows; sources: Cadence DE-HDL packaged netlist, KiCad conversion of 03242023_DA0F0TMBIJ0_F0T_Motherboard_J_brd_V01_OCP.brd

PC532  Q_CAP  100NF 50V 10% X7R  pkg C0402  page 286 : A = SW_PVCCIN_CPU1_BOOT3_R ; B = SW_PVCCIN_CPU1_BOOTR3
R3866  Q_RES  0 5% CHIP  pkg 0402LF  page 250 : A = P12V_OCP_SFF_ISENSE_MPS_TIC ; B = P12V_OCP_SFF_ISENSE_TIC

(kicad_pcb
	(version 20260206)
	(generator "pcbnew")
	(generator_version "10.0")
	(general
		(thickness 1.6)
		(legacy_teardrops no)
	)
	(paper "A4")
	(title_block
		(title "03242023_DA0F0TMBIJ0_F0T_Motherboard_J_brd_V01_OCP.brd")
		(comment 1 "Grand Teton / footprints 315-316 of 6105")
	)
	(layers
		(0 "F.Cu" signal "TOP")
		(4 "In1.Cu" signal "GND")
		(6 "In2.Cu" signal "IN1")
		(8 "In3.Cu" signal "GND1")
		(10 "In4.Cu" signal "IN2")
		(12 "In5.Cu" signal "GND2")
		(14 "In6.Cu" signal "IN3")
		(16 "In7.Cu" signal "GND3")
		(18 "In8.Cu" signal "VCC")
		(20 "In9.Cu" signal "VCC1")
		(22 "In10.Cu" signal "GND4")
		(24 "In11.Cu" signal "IN4")
		(26 "In12.Cu" signal "GND5")
		(28 "In13.Cu" signal "IN5")
		(30 "In14.Cu" signal "GND6")
		(32 "In15.Cu" signal "IN6")
		(34 "In16.Cu" signal "GND7")
		(2 "B.Cu" signal "BOTTOM")
		(9 "F.Adhes" user "F.Adhesive")
		(11 "B.Adhes" user "B.Adhesive")
		(13 "F.Paste" user "Package Geometry/Pastemask Top")
		(15 "B.Paste" user "Package Geometry/Pastemask Bottom")
		(5 "F.SilkS" user "Ref Des/Silkscreen Top")
		(7 "B.SilkS" user "Ref Des/Silkscreen Bottom")
		(1 "F.Mask" user "Board Geometry/Soldermask Top")
		(3 "B.Mask" user "Board Geometry/Soldermask Bottom")
		(17 "Dwgs.User" user "User.Drawings")
		(19 "Cmts.User" user "User.Comments")
		(21 "Eco1.User" user "User.Eco1")
		(23 "Eco2.User" user "User.Eco2")
		(25 "Edge.Cuts" user "Board Geometry/Outline")
		(27 "Margin" user)
		(31 "F.CrtYd" user "Package Geometry/Place Bound Top")
		(29 "B.CrtYd" user "Package Geometry/Place Bound Bottom")
		(35 "F.Fab" user "Ref Des/Assembly Top")
		(33 "B.Fab" user "Ref Des/Assembly Bottom")
	)
	(footprint ""
		(layer "F.Cu")
		(at 39.827454 -111.606838)
		(property "Reference" "R3866"
			(at 0 0 0)
			(layer "F.SilkS")
			(hide yes)
			(effects
				(font
					(size 1.27 1.27)
				)
			)
		)
		(property "Value" ""
			(at 0 0 0)
			(layer "F.Fab")
			(effects
				(font
					(size 1.27 1.27)
				)
			)
		)
		(duplicate_pad_numbers_are_jumpers no)
		(fp_line
			(start -0.7874 -0.4064)
			(end 0.7874 -0.4064)
			(stroke
				(width 0.1524)
				(type default)
			)
			(layer "F.SilkS")
		)
		(fp_line
			(start -0.7874 0.4064)
			(end -0.7874 -0.4064)
			(stroke
				(width 0.1524)
				(type default)
			)
			(layer "F.SilkS")
		)
		(fp_line
			(start 0.7874 -0.4064)
			(end 0.7874 0.4064)
			(stroke
				(width 0.1524)
				(type default)
			)
			(layer "F.SilkS")
		)
		(fp_line
			(start 0.7874 0.4064)
			(end -0.7874 0.4064)
			(stroke
				(width 0.1524)
				(type default)
			)
			(layer "F.SilkS")
		)
		(fp_line
			(start -0.67945 -0.305054)
			(end -0.12065 -0.305054)
			(stroke
				(width 0.1)
				(type default)
			)
			(layer "F.Fab")
		)
		(fp_line
			(start -0.67945 0.3048)
			(end -0.67945 -0.305054)
			(stroke
				(width 0.1)
				(type default)
			)
			(layer "F.Fab")
		)
		(fp_line
			(start -0.12065 -0.305054)
			(end -0.12065 -0.2794)
			(stroke
				(width 0.1)
				(type default)
			)
			(layer "F.Fab")
		)
		(fp_line
			(start -0.12065 -0.2794)
			(end 0.12065 -0.2794)
			(stroke
				(width 0.1)
				(type default)
			)
			(layer "F.Fab")
		)
		(fp_line
			(start -0.12065 0.2794)
			(end -0.12065 0.3048)
			(stroke
				(width 0.1)
				(type default)
			)
			(layer "F.Fab")
		)
		(fp_line
			(start -0.12065 0.3048)
			(end -0.67945 0.3048)
			(stroke
				(width 0.1)
				(type default)
			)
			(layer "F.Fab")
		)
		(fp_line
			(start 0.120396 0.2794)
			(end -0.12065 0.2794)
			(stroke
				(width 0.1)
				(type default)
			)
			(layer "F.Fab")
		)
		(fp_line
			(start 0.120396 0.3048)
			(end 0.120396 0.2794)
			(stroke
				(width 0.1)
				(type default)
			)
			(layer "F.Fab")
		)
		(fp_line
			(start 0.12065 -0.3048)
			(end 0.67945 -0.3048)
			(stroke
				(width 0.1)
				(type default)
			)
			(layer "F.Fab")
		)
		(fp_line
			(start 0.12065 -0.2794)
			(end 0.12065 -0.3048)
			(stroke
				(width 0.1)
				(type default)
			)
			(layer "F.Fab")
		)
		(fp_line
			(start 0.67945 -0.3048)
			(end 0.67945 0.3048)
			(stroke
				(width 0.1)
				(type default)
			)
			(layer "F.Fab")
		)
		(fp_line
			(start 0.67945 0.3048)
			(end 0.120396 0.3048)
			(stroke
				(width 0.1)
				(type default)
			)
			(layer "F.Fab")
		)
		(pad "1" smd rect
			(at -0.40005 0 180)
			(size 0.4572 0.508)
			(layers "F.Cu" "F.Mask" "F.Paste")
			(net "P12V_OCP_SFF_ISENSE_MPS_TIC")
		)
		(pad "2" smd rect
			(at 0.40005 0 180)
			(size 0.4572 0.508)
			(layers "F.Cu" "F.Mask" "F.Paste")
			(net "P12V_OCP_SFF_ISENSE_TIC")
		)
	)
	(footprint ""
		(layer "F.Cu")
		(at 115.052094 -338.17814 -90)
		(property "Reference" "PC532"
			(at 0 0 270)
			(layer "F.SilkS")
			(hide yes)
			(effects
				(font
					(size 1.27 1.27)
				)
			)
		)
		(property "Value" ""
			(at 0 0 270)
			(layer "F.Fab")
			(effects
				(font
					(size 1.27 1.27)
				)
			)
		)
		(duplicate_pad_numbers_are_jumpers no)
		(fp_line
			(start -0.7874 0.4064)
			(end -0.7874 -0.4064)
			(stroke
				(width 0.1524)
				(type default)
			)
			(layer "F.SilkS")
		)
		(fp_line
			(start 0.7874 0.4064)
			(end -0.7874 0.4064)
			(stroke
				(width 0.1524)
				(type default)
			)
			(layer "F.SilkS")
		)
		(fp_line
			(start -0.7874 -0.4064)
			(end 0.7874 -0.4064)
			(stroke
				(width 0.1524)
				(type default)
			)
			(layer "F.SilkS")
		)
		(fp_line
			(start 0.7874 -0.4064)
			(end 0.7874 0.4064)
			(stroke
				(width 0.1524)
				(type default)
			)
			(layer "F.SilkS")
		)
		(fp_line
			(start -0.67945 0.3048)
			(end -0.67945 -0.305054)
			(stroke
				(width 0.1)
				(type default)
			)
			(layer "F.Fab")
		)
		(fp_line
			(start -0.12065 0.3048)
			(end -0.67945 0.3048)
			(stroke
				(width 0.1)
				(type default)
			)
			(layer "F.Fab")
		)
		(fp_line
			(start 0.120396 0.3048)
			(end 0.120396 0.2794)
			(stroke
				(width 0.1)
				(type default)
			)
			(layer "F.Fab")
		)
		(fp_line
			(start 0.67945 0.3048)
			(end 0.120396 0.3048)
			(stroke
				(width 0.1)
				(type default)
			)
			(layer "F.Fab")
		)
		(fp_line
			(start -0.12065 0.2794)
			(end -0.12065 0.3048)
			(stroke
				(width 0.1)
				(type default)
			)
			(layer "F.Fab")
		)
		(fp_line
			(start 0.120396 0.2794)
			(end -0.12065 0.2794)
			(stroke
				(width 0.1)
				(type default)
			)
			(layer "F.Fab")
		)
		(fp_line
			(start -0.12065 -0.2794)
			(end 0.12065 -0.2794)
			(stroke
				(width 0.1)
				(type default)
			)
			(layer "F.Fab")
		)
		(fp_line
			(start 0.12065 -0.2794)
			(end 0.12065 -0.3048)
			(stroke
				(width 0.1)
				(type default)
			)
			(layer "F.Fab")
		)
		(fp_line
			(start 0.12065 -0.3048)
			(end 0.67945 -0.3048)
			(stroke
				(width 0.1)
				(type default)
			)
			(layer "F.Fab")
		)
		(fp_line
			(start 0.67945 -0.3048)
			(end 0.67945 0.3048)
			(stroke
				(width 0.1)
				(type default)
			)
			(layer "F.Fab")
		)
		(fp_line
			(start -0.67945 -0.305054)
			(end -0.12065 -0.305054)
			(stroke
				(width 0.1)
				(type default)
			)
			(layer "F.Fab")
		)
		(fp_line
			(start -0.12065 -0.305054)
			(end -0.12065 -0.2794)
			(stroke
				(width 0.1)
				(type default)
			)
			(layer "F.Fab")
		)
		(pad "1" smd circle
			(at -0.40005 0 270)
			(size 0 0)
			(layers "F.Cu" "F.Mask" "F.Paste")
			(net "SW_PVCCIN_CPU1_BOOT3_R")
		)
		(pad "2" smd circle
			(at 0.40005 0 270)
			(size 0 0)
			(layers "F.Cu" "F.Mask" "F.Paste")
			(net "SW_PVCCIN_CPU1_BOOTR3")
		)
	)
)
